(kicad_pcb
	(version 20260206)
	(generator "pcbnew")
	(generator_version "10.0")
	(general
		(thickness 1.6)
		(legacy_teardrops no)
	)
	(paper "A4")
	(title_block
		(title "peb — Lightning_PEB_BRD.brd")
		(comment 1 "Lightning (Wiwynn / Facebook NVMe JBOF) / footprints 2379-2386 of 2563")
	)
	(layers
		(0 "F.Cu" signal "TOP")
		(4 "In1.Cu" signal "L2GND")
		(6 "In2.Cu" signal "L3")
		(8 "In3.Cu" signal "L4VCC")
		(10 "In4.Cu" signal "L5VCC")
		(12 "In5.Cu" signal "L6")
		(14 "In6.Cu" signal "L7GND")
		(2 "B.Cu" signal "BOTTOM")
		(9 "F.Adhes" user "F.Adhesive")
		(11 "B.Adhes" user "B.Adhesive")
		(13 "F.Paste" user "Package Geometry/Pastemask Top")
		(15 "B.Paste" user "Package Geometry/Pastemask Bottom")
		(5 "F.SilkS" user "Ref Des/Silkscreen Top")
		(7 "B.SilkS" user "Ref Des/Silkscreen Bottom")
		(1 "F.Mask" user "Board Geometry/Soldermask Top")
		(3 "B.Mask" user "Board Geometry/Soldermask Bottom")
		(17 "Dwgs.User" user "User.Drawings")
		(19 "Cmts.User" user "User.Comments")
		(21 "Eco1.User" user "User.Eco1")
		(23 "Eco2.User" user "User.Eco2")
		(25 "Edge.Cuts" user "Board Geometry/Outline")
		(27 "Margin" user)
		(31 "F.CrtYd" user "Package Geometry/Place Bound Top")
		(29 "B.CrtYd" user "Package Geometry/Place Bound Bottom")
		(35 "F.Fab" user "Ref Des/Assembly Top")
		(33 "B.Fab" user "Ref Des/Assembly Bottom")
	)
	(footprint ""
		(layer "B.Cu")
		(at 242.824 -23.241 180)
		(property "Reference" "R780"
			(at 0 0 0)
			(layer "B.SilkS")
			(hide yes)
			(effects
				(font
					(size 1.27 1.27)
				)
				(justify mirror)
			)
		)
		(property "Value" "4K7R2F-GP"
			(at -0.064008 -3.993896 180)
			(unlocked yes)
			(layer "B.Fab")
			(hide yes)
			(effects
				(font
					(size 1.016 1.016)
					(thickness 0.1524)
				)
				(justify mirror)
			)
		)
		(property "Device Type" "R402H16"
			(at -0.064008 -5.517896 180)
			(unlocked yes)
			(layer "B.Fab")
			(hide yes)
			(effects
				(font
					(size 1.016 1.016)
					(thickness 0.1524)
				)
				(justify mirror)
			)
		)
		(duplicate_pad_numbers_are_jumpers no)
		(fp_line
			(start 0.508 -0.9398)
			(end 0.508 0.9398)
			(stroke
				(width 0.1524)
				(type default)
			)
			(layer "B.SilkS")
		)
		(fp_line
			(start -0.508 -0.9398)
			(end 0.508 -0.9398)
			(stroke
				(width 0.1524)
				(type default)
			)
			(layer "B.SilkS")
		)
		(fp_rect
			(start 0.508 0.9398)
			(end -0.508 -0.9398)
			(stroke
				(width 0)
				(type default)
			)
			(fill no)
			(layer "B.CrtYd")
		)
		(fp_rect
			(start 0.508 0.9398)
			(end -0.508 -0.9398)
			(stroke
				(width 0)
				(type default)
			)
			(fill no)
			(layer "B.Fab")
		)
		(pad "1" smd custom
			(at 0 -0.4445)
			(size 0.1397 0.1397)
			(layers "B.Cu" "B.Mask" "B.Paste")
			(net "BOOTSTRAP0")
			(options
				(clearance outline)
				(anchor circle)
			)
			(primitives
				(gr_poly
					(pts
						(arc
							(start -0.1778 0.2794)
							(mid -0.249642 0.249642)
							(end -0.2794 0.1778)
						)
						(arc
							(start -0.2794 -0.1778)
							(mid -0.249642 -0.249642)
							(end -0.1778 -0.2794)
						)
						(arc
							(start 0.1778 -0.2794)
							(mid 0.249642 -0.249642)
							(end 0.2794 -0.1778)
						)
						(arc
							(start 0.2794 0.1778)
							(mid 0.249642 0.249642)
							(end 0.1778 0.2794)
						)
					)
					(width 0)
					(fill yes)
				)
			)
		)
		(pad "2" smd custom
			(at 0 0.4445)
			(size 0.1397 0.1397)
			(layers "B.Cu" "B.Mask" "B.Paste")
			(net "BOOTSTRAP_R_0")
			(options
				(clearance outline)
				(anchor circle)
			)
			(primitives
				(gr_poly
					(pts
						(arc
							(start -0.1778 0.2794)
							(mid -0.249642 0.249642)
							(end -0.2794 0.1778)
						)
						(arc
							(start -0.2794 -0.1778)
							(mid -0.249642 -0.249642)
							(end -0.1778 -0.2794)
						)
						(arc
							(start 0.1778 -0.2794)
							(mid 0.249642 -0.249642)
							(end 0.2794 -0.1778)
						)
						(arc
							(start 0.2794 0.1778)
							(mid 0.249642 0.249642)
							(end 0.1778 0.2794)
						)
					)
					(width 0)
					(fill yes)
				)
			)
		)
	)
	(footprint ""
		(layer "B.Cu")
		(at 310.007 -57.785 180)
		(property "Reference" "PG39"
			(at 0 0 0)
			(layer "B.SilkS")
			(hide yes)
			(effects
				(font
					(size 1.27 1.27)
				)
				(justify mirror)
			)
		)
		(property "Value" "GAP-CLOSE-PWR-3-GP"
			(at -0.0254 -6.5786 180)
			(unlocked yes)
			(layer "B.Fab")
			(hide yes)
			(effects
				(font
					(size 1.016 1.016)
					(thickness 0.1524)
				)
				(justify mirror)
			)
		)
		(property "Device Type" "GAP-CLOSE-PWR-3"
			(at -0.0254 -8.255 180)
			(unlocked yes)
			(layer "B.Fab")
			(hide yes)
			(effects
				(font
					(size 1.016 1.016)
					(thickness 0.1524)
				)
				(justify mirror)
			)
		)
		(duplicate_pad_numbers_are_jumpers no)
		(fp_rect
			(start 0.7112 0.4572)
			(end -0.7112 -0.4572)
			(stroke
				(width 0)
				(type default)
			)
			(fill no)
			(layer "B.CrtYd")
		)
		(fp_poly
			(pts
				(xy 0.7112 -0.4572) (xy -0.7112 -0.4572) (xy -0.7112 0.4572) (xy 0.7112 0.4572)
			)
			(stroke
				(width 0)
				(type default)
			)
			(fill no)
			(layer "B.Fab")
		)
		(pad "1" smd rect
			(at 0.3048 0)
			(size 0.6604 0.762)
			(layers "B.Cu" "B.Mask" "B.Paste")
			(net "DUT_VDD")
		)
		(pad "2" smd rect
			(at -0.3048 0)
			(size 0.6604 0.762)
			(layers "B.Cu" "B.Mask" "B.Paste")
			(net "P0V9_E")
		)
	)
	(footprint ""
		(layer "B.Cu")
		(at 245.5926 -32.004)
		(property "Reference" "C472"
			(at 0 0 0)
			(layer "B.SilkS")
			(hide yes)
			(effects
				(font
					(size 1.27 1.27)
				)
				(justify mirror)
			)
		)
		(property "Value" "SCD1U16V1KX-1-GP"
			(at 2.8321 -1.7399 0)
			(unlocked yes)
			(layer "B.Fab")
			(hide yes)
			(effects
				(font
					(size 1.016 1.016)
					(thickness 0.1524)
				)
				(justify mirror)
			)
		)
		(property "Device Type" "C0201H13"
			(at 2.8321 -3.2639 0)
			(unlocked yes)
			(layer "B.Fab")
			(hide yes)
			(effects
				(font
					(size 1.016 1.016)
					(thickness 0.1524)
				)
				(justify mirror)
			)
		)
		(duplicate_pad_numbers_are_jumpers no)
		(fp_rect
			(start 0.2794 0.6477)
			(end -0.2794 -0.6477)
			(stroke
				(width 0)
				(type default)
			)
			(fill no)
			(layer "B.CrtYd")
		)
		(fp_rect
			(start 0.2794 0.6477)
			(end -0.2794 -0.6477)
			(stroke
				(width 0)
				(type default)
			)
			(fill no)
			(layer "B.Fab")
		)
		(pad "1" smd custom
			(at 0 -0.2794 180)
			(size 0.0762 0.0762)
			(layers "B.Cu" "B.Mask" "B.Paste")
			(net "DUT_VDDO")
			(options
				(clearance outline)
				(anchor circle)
			)
			(primitives
				(gr_poly
					(pts
						(arc
							(start 0.1524 0.127)
							(mid 0.137521 0.162921)
							(end 0.1016 0.1778)
						)
						(arc
							(start -0.1016 0.1778)
							(mid -0.137521 0.162921)
							(end -0.1524 0.127)
						)
						(arc
							(start -0.1524 -0.127)
							(mid -0.137521 -0.162921)
							(end -0.1016 -0.1778)
						)
						(arc
							(start 0.1016 -0.1778)
							(mid 0.137521 -0.162921)
							(end 0.1524 -0.127)
						)
					)
					(width 0)
					(fill yes)
				)
			)
		)
		(pad "2" smd custom
			(at 0 0.2794 180)
			(size 0.0762 0.0762)
			(layers "B.Cu" "B.Mask" "B.Paste")
			(net "GND")
			(options
				(clearance outline)
				(anchor circle)
			)
			(primitives
				(gr_poly
					(pts
						(arc
							(start 0.1524 0.127)
							(mid 0.137521 0.162921)
							(end 0.1016 0.1778)
						)
						(arc
							(start -0.1016 0.1778)
							(mid -0.137521 0.162921)
							(end -0.1524 0.127)
						)
						(arc
							(start -0.1524 -0.127)
							(mid -0.137521 -0.162921)
							(end -0.1016 -0.1778)
						)
						(arc
							(start 0.1016 -0.1778)
							(mid 0.137521 -0.162921)
							(end 0.1524 -0.127)
						)
					)
					(width 0)
					(fill yes)
				)
			)
		)
	)
	(footprint ""
		(layer "B.Cu")
		(at 132.588 -202.819)
		(property "Reference" "U66"
			(at 0 0 0)
			(layer "B.SilkS")
			(hide yes)
			(effects
				(font
					(size 1.27 1.27)
				)
				(justify mirror)
			)
		)
		(property "Value" "SN74LVC1G08DCKR-GP"
			(at 2.3368 -8.6868 0)
			(unlocked yes)
			(layer "B.Fab")
			(hide yes)
			(effects
				(font
					(size 1.016 1.016)
					(thickness 0.1524)
				)
				(justify mirror)
			)
		)
		(property "Device Type" "SC70-5H44"
			(at 2.3114 -10.414 0)
			(unlocked yes)
			(layer "B.Fab")
			(hide yes)
			(effects
				(font
					(size 1.016 1.016)
					(thickness 0.1524)
				)
				(justify mirror)
			)
		)
		(duplicate_pad_numbers_are_jumpers no)
		(fp_line
			(start -1.3843 -1.8034)
			(end -1.3843 -1.1176)
			(stroke
				(width 0.3302)
				(type default)
			)
			(layer "B.SilkS")
		)
		(fp_line
			(start -1.27 -1.7018)
			(end -1.27 1.7018)
			(stroke
				(width 0.1524)
				(type default)
			)
			(layer "B.SilkS")
		)
		(fp_line
			(start -1.27 1.7018)
			(end 1.27 1.7018)
			(stroke
				(width 0.1524)
				(type default)
			)
			(layer "B.SilkS")
		)
		(fp_line
			(start -0.6604 -1.8034)
			(end -1.3843 -1.8034)
			(stroke
				(width 0.3302)
				(type default)
			)
			(layer "B.SilkS")
		)
		(fp_line
			(start 1.27 -1.7018)
			(end -1.27 -1.7018)
			(stroke
				(width 0.1524)
				(type default)
			)
			(layer "B.SilkS")
		)
		(fp_line
			(start 1.27 1.7018)
			(end 1.27 -1.7018)
			(stroke
				(width 0.1524)
				(type default)
			)
			(layer "B.SilkS")
		)
		(fp_rect
			(start 1.524 1.9558)
			(end -1.524 -1.9558)
			(stroke
				(width 0)
				(type default)
			)
			(fill no)
			(layer "B.CrtYd")
		)
		(fp_poly
			(pts
				(xy 1.524 -1.9558) (xy -1.524 -1.9558) (xy -1.524 1.9558) (xy 1.524 1.9558)
			)
			(stroke
				(width 0)
				(type default)
			)
			(fill no)
			(layer "B.Fab")
		)
		(pad "1" smd rect
			(at -0.65024 -0.8255 180)
			(size 0.4064 1.2192)
			(layers "B.Cu" "B.Mask" "B.Paste")
			(net "BMC_SSD_RST#0_A2")
		)
		(pad "2" smd rect
			(at 0 -0.8255 180)
			(size 0.4064 1.2192)
			(layers "B.Cu" "B.Mask" "B.Paste")
			(net "SSD_PERST#0_B2")
		)
		(pad "3" smd rect
			(at 0.65024 -0.8255 180)
			(size 0.4064 1.2192)
			(layers "B.Cu" "B.Mask" "B.Paste")
			(net "GND")
		)
		(pad "4" smd rect
			(at 0.65024 0.8255 180)
			(size 0.4064 1.2192)
			(layers "B.Cu" "B.Mask" "B.Paste")
			(net "SSD_PERST_Y2")
		)
		(pad "5" smd rect
			(at -0.65024 0.8255 180)
			(size 0.4064 1.2192)
			(layers "B.Cu" "B.Mask" "B.Paste")
			(net "P3V3_STBY")
		)
	)
	(footprint ""
		(layer "B.Cu")
		(at 245.5926 -57.9882 90)
		(property "Reference" "C501"
			(at 0 0 90)
			(layer "B.SilkS")
			(hide yes)
			(effects
				(font
					(size 1.27 1.27)
				)
				(justify mirror)
			)
		)
		(property "Value" "SCD1U16V1KX-1-GP"
			(at 2.8321 -1.7399 90)
			(unlocked yes)
			(layer "B.Fab")
			(hide yes)
			(effects
				(font
					(size 1.016 1.016)
					(thickness 0.1524)
				)
				(justify mirror)
			)
		)
		(property "Device Type" "C0201H13"
			(at 2.8321 -3.2639 90)
			(unlocked yes)
			(layer "B.Fab")
			(hide yes)
			(effects
				(font
					(size 1.016 1.016)
					(thickness 0.1524)
				)
				(justify mirror)
			)
		)
		(duplicate_pad_numbers_are_jumpers no)
		(fp_rect
			(start 0.2794 0.6477)
			(end -0.2794 -0.6477)
			(stroke
				(width 0)
				(type default)
			)
			(fill no)
			(layer "B.CrtYd")
		)
		(fp_rect
			(start 0.2794 0.6477)
			(end -0.2794 -0.6477)
			(stroke
				(width 0)
				(type default)
			)
			(fill no)
			(layer "B.Fab")
		)
		(pad "1" smd custom
			(at 0 -0.2794 270)
			(size 0.0762 0.0762)
			(layers "B.Cu" "B.Mask" "B.Paste")
			(net "DUT_AVD_TX")
			(options
				(clearance outline)
				(anchor circle)
			)
			(primitives
				(gr_poly
					(pts
						(arc
							(start 0.1524 0.127)
							(mid 0.137521 0.162921)
							(end 0.1016 0.1778)
						)
						(arc
							(start -0.1016 0.1778)
							(mid -0.137521 0.162921)
							(end -0.1524 0.127)
						)
						(arc
							(start -0.1524 -0.127)
							(mid -0.137521 -0.162921)
							(end -0.1016 -0.1778)
						)
						(arc
							(start 0.1016 -0.1778)
							(mid 0.137521 -0.162921)
							(end 0.1524 -0.127)
						)
					)
					(width 0)
					(fill yes)
				)
			)
		)
		(pad "2" smd custom
			(at 0 0.2794 270)
			(size 0.0762 0.0762)
			(layers "B.Cu" "B.Mask" "B.Paste")
			(net "GND")
			(options
				(clearance outline)
				(anchor circle)
			)
			(primitives
				(gr_poly
					(pts
						(arc
							(start 0.1524 0.127)
							(mid 0.137521 0.162921)
							(end 0.1016 0.1778)
						)
						(arc
							(start -0.1016 0.1778)
							(mid -0.137521 0.162921)
							(end -0.1524 0.127)
						)
						(arc
							(start -0.1524 -0.127)
							(mid -0.137521 -0.162921)
							(end -0.1016 -0.1778)
						)
						(arc
							(start 0.1016 -0.1778)
							(mid 0.137521 -0.162921)
							(end 0.1524 -0.127)
						)
					)
					(width 0)
					(fill yes)
				)
			)
		)
	)
	(footprint ""
		(layer "B.Cu")
		(at 235.585 -59.99734 -90)
		(property "Reference" "C525"
			(at 0 0 90)
			(layer "B.SilkS")
			(hide yes)
			(effects
				(font
					(size 1.27 1.27)
				)
				(justify mirror)
			)
		)
		(property "Value" "SCD1U16V1KX-1-GP"
			(at 2.8321 -1.7399 270)
			(unlocked yes)
			(layer "B.Fab")
			(hide yes)
			(effects
				(font
					(size 1.016 1.016)
					(thickness 0.1524)
				)
				(justify mirror)
			)
		)
		(property "Device Type" "C0201H13"
			(at 2.8321 -3.2639 270)
			(unlocked yes)
			(layer "B.Fab")
			(hide yes)
			(effects
				(font
					(size 1.016 1.016)
					(thickness 0.1524)
				)
				(justify mirror)
			)
		)
		(duplicate_pad_numbers_are_jumpers no)
		(fp_rect
			(start 0.2794 0.6477)
			(end -0.2794 -0.6477)
			(stroke
				(width 0)
				(type default)
			)
			(fill no)
			(layer "B.CrtYd")
		)
		(fp_rect
			(start 0.2794 0.6477)
			(end -0.2794 -0.6477)
			(stroke
				(width 0)
				(type default)
			)
			(fill no)
			(layer "B.Fab")
		)
		(pad "1" smd custom
			(at 0 -0.2794 90)
			(size 0.0762 0.0762)
			(layers "B.Cu" "B.Mask" "B.Paste")
			(net "DUT_AVD_TX")
			(options
				(clearance outline)
				(anchor circle)
			)
			(primitives
				(gr_poly
					(pts
						(arc
							(start 0.1524 0.127)
							(mid 0.137521 0.162921)
							(end 0.1016 0.1778)
						)
						(arc
							(start -0.1016 0.1778)
							(mid -0.137521 0.162921)
							(end -0.1524 0.127)
						)
						(arc
							(start -0.1524 -0.127)
							(mid -0.137521 -0.162921)
							(end -0.1016 -0.1778)
						)
						(arc
							(start 0.1016 -0.1778)
							(mid 0.137521 -0.162921)
							(end 0.1524 -0.127)
						)
					)
					(width 0)
					(fill yes)
				)
			)
		)
		(pad "2" smd custom
			(at 0 0.2794 90)
			(size 0.0762 0.0762)
			(layers "B.Cu" "B.Mask" "B.Paste")
			(net "GND")
			(options
				(clearance outline)
				(anchor circle)
			)
			(primitives
				(gr_poly
					(pts
						(arc
							(start 0.1524 0.127)
							(mid 0.137521 0.162921)
							(end 0.1016 0.1778)
						)
						(arc
							(start -0.1016 0.1778)
							(mid -0.137521 0.162921)
							(end -0.1524 0.127)
						)
						(arc
							(start -0.1524 -0.127)
							(mid -0.137521 -0.162921)
							(end -0.1016 -0.1778)
						)
						(arc
							(start 0.1016 -0.1778)
							(mid 0.137521 -0.162921)
							(end 0.1524 -0.127)
						)
					)
					(width 0)
					(fill yes)
				)
			)
		)
	)
	(footprint ""
		(layer "B.Cu")
		(at 242.130072 -39.996872 -90)
		(property "Reference" "C486"
			(at 0 0 90)
			(layer "B.SilkS")
			(hide yes)
			(effects
				(font
					(size 1.27 1.27)
				)
				(justify mirror)
			)
		)
		(property "Value" "SCD1U16V1KX-1-GP"
			(at 2.8321 -1.7399 270)
			(unlocked yes)
			(layer "B.Fab")
			(hide yes)
			(effects
				(font
					(size 1.016 1.016)
					(thickness 0.1524)
				)
				(justify mirror)
			)
		)
		(property "Device Type" "C0201H13"
			(at 2.8321 -3.2639 270)
			(unlocked yes)
			(layer "B.Fab")
			(hide yes)
			(effects
				(font
					(size 1.016 1.016)
					(thickness 0.1524)
				)
				(justify mirror)
			)
		)
		(duplicate_pad_numbers_are_jumpers no)
		(fp_rect
			(start 0.2794 0.6477)
			(end -0.2794 -0.6477)
			(stroke
				(width 0)
				(type default)
			)
			(fill no)
			(layer "B.CrtYd")
		)
		(fp_rect
			(start 0.2794 0.6477)
			(end -0.2794 -0.6477)
			(stroke
				(width 0)
				(type default)
			)
			(fill no)
			(layer "B.Fab")
		)
		(pad "1" smd custom
			(at 0 -0.2794 90)
			(size 0.0762 0.0762)
			(layers "B.Cu" "B.Mask" "B.Paste")
			(net "DUT_VDDO")
			(options
				(clearance outline)
				(anchor circle)
			)
			(primitives
				(gr_poly
					(pts
						(arc
							(start 0.1524 0.127)
							(mid 0.137521 0.162921)
							(end 0.1016 0.1778)
						)
						(arc
							(start -0.1016 0.1778)
							(mid -0.137521 0.162921)
							(end -0.1524 0.127)
						)
						(arc
							(start -0.1524 -0.127)
							(mid -0.137521 -0.162921)
							(end -0.1016 -0.1778)
						)
						(arc
							(start 0.1016 -0.1778)
							(mid 0.137521 -0.162921)
							(end 0.1524 -0.127)
						)
					)
					(width 0)
					(fill yes)
				)
			)
		)
		(pad "2" smd custom
			(at 0 0.2794 90)
			(size 0.0762 0.0762)
			(layers "B.Cu" "B.Mask" "B.Paste")
			(net "GND")
			(options
				(clearance outline)
				(anchor circle)
			)
			(primitives
				(gr_poly
					(pts
						(arc
							(start 0.1524 0.127)
							(mid 0.137521 0.162921)
							(end 0.1016 0.1778)
						)
						(arc
							(start -0.1016 0.1778)
							(mid -0.137521 0.162921)
							(end -0.1524 0.127)
						)
						(arc
							(start -0.1524 -0.127)
							(mid -0.137521 -0.162921)
							(end -0.1016 -0.1778)
						)
						(arc
							(start 0.1016 -0.1778)
							(mid 0.137521 -0.162921)
							(end 0.1524 -0.127)
						)
					)
					(width 0)
					(fill yes)
				)
			)
		)
	)
	(footprint ""
		(layer "B.Cu")
		(at 61.4426 -120.2944 90)
		(property "Reference" "R306"
			(at 0 0 90)
			(layer "B.SilkS")
			(hide yes)
			(effects
				(font
					(size 1.27 1.27)
				)
				(justify mirror)
			)
		)
		(property "Value" "4K7R2F-GP"
			(at -0.064008 -3.993896 90)
			(unlocked yes)
			(layer "B.Fab")
			(hide yes)
			(effects
				(font
					(size 1.016 1.016)
					(thickness 0.1524)
				)
				(justify mirror)
			)
		)
		(property "Device Type" "R402H16"
			(at -0.064008 -5.517896 90)
			(unlocked yes)
			(layer "B.Fab")
			(hide yes)
			(effects
				(font
					(size 1.016 1.016)
					(thickness 0.1524)
				)
				(justify mirror)
			)
		)
		(duplicate_pad_numbers_are_jumpers no)
		(fp_line
			(start 0.508 -0.9398)
			(end 0.508 0.9398)
			(stroke
				(width 0.1524)
				(type default)
			)
			(layer "B.SilkS")
		)
		(fp_line
			(start -0.508 -0.9398)
			(end 0.508 -0.9398)
			(stroke
				(width 0.1524)
				(type default)
			)
			(layer "B.SilkS")
		)
		(fp_rect
			(start 0.508 0.9398)
			(end -0.508 -0.9398)
			(stroke
				(width 0)
				(type default)
			)
			(fill no)
			(layer "B.CrtYd")
		)
		(fp_rect
			(start 0.508 0.9398)
			(end -0.508 -0.9398)
			(stroke
				(width 0)
				(type default)
			)
			(fill no)
			(layer "B.Fab")
		)
		(pad "1" smd custom
			(at 0 -0.4445 270)
			(size 0.1397 0.1397)
			(layers "B.Cu" "B.Mask" "B.Paste")
			(net "P3V3_STBY")
			(options
				(clearance outline)
				(anchor circle)
			)
			(primitives
				(gr_poly
					(pts
						(arc
							(start -0.1778 0.2794)
							(mid -0.249642 0.249642)
							(end -0.2794 0.1778)
						)
						(arc
							(start -0.2794 -0.1778)
							(mid -0.249642 -0.249642)
							(end -0.1778 -0.2794)
						)
						(arc
							(start 0.1778 -0.2794)
							(mid 0.249642 -0.249642)
							(end 0.2794 -0.1778)
						)
						(arc
							(start 0.2794 0.1778)
							(mid 0.249642 0.249642)
							(end 0.1778 0.2794)
						)
					)
					(width 0)
					(fill yes)
				)
			)
		)
		(pad "2" smd custom
			(at 0 0.4445 270)
			(size 0.1397 0.1397)
			(layers "B.Cu" "B.Mask" "B.Paste")
			(net "I2C3_LS_G1")
			(options
				(clearance outline)
				(anchor circle)
			)
			(primitives
				(gr_poly
					(pts
						(arc
							(start -0.1778 0.2794)
							(mid -0.249642 0.249642)
							(end -0.2794 0.1778)
						)
						(arc
							(start -0.2794 -0.1778)
							(mid -0.249642 -0.249642)
							(end -0.1778 -0.2794)
						)
						(arc
							(start 0.1778 -0.2794)
							(mid 0.249642 -0.249642)
							(end 0.2794 -0.1778)
						)
						(arc
							(start 0.2794 0.1778)
							(mid 0.249642 0.249642)
							(end 0.1778 0.2794)
						)
					)
					(width 0)
					(fill yes)
				)
			)
		)
	)
)
